# S9S_MB_2U (Grand Teton) — schematic netlist excerpt (pin names and nets, part order shuffled) for the footprints in the layout excerpt that follows; sources: Cadence DE-HDL packaged netlist, KiCad conversion of 03242023_DA0F0TMBIJ0_F0T_Motherboard_J_brd_V01_OCP.brd

C1400  Q_CAP  47UF 4V 20% X6S  pkg C0805  page 76 : A = PVNN_MAIN_CPU0 ; B = GND
PR1777  Q_RES  0 5% CHIP  pkg 0402LF  page 275 : A = PVCCINFAON_CPU0_VOS2 ; B = PVCCINFAON_CPU0
PR101  Q_RES  2.2 1% CHIP  pkg 0402LF  page 275 : A = PVCCFA_EHV_CPU0_PVCC ; B = PVCCINFAON_CPU0_VDD1

(kicad_pcb
	(version 20260206)
	(generator "pcbnew")
	(generator_version "10.0")
	(general
		(thickness 1.6)
		(legacy_teardrops no)
	)
	(paper "A4")
	(title_block
		(title "03242023_DA0F0TMBIJ0_F0T_Motherboard_J_brd_V01_OCP.brd")
		(comment 1 "Grand Teton / footprints 4524-4526 of 6105")
	)
	(layers
		(0 "F.Cu" signal "TOP")
		(4 "In1.Cu" signal "GND")
		(6 "In2.Cu" signal "IN1")
		(8 "In3.Cu" signal "GND1")
		(10 "In4.Cu" signal "IN2")
		(12 "In5.Cu" signal "GND2")
		(14 "In6.Cu" signal "IN3")
		(16 "In7.Cu" signal "GND3")
		(18 "In8.Cu" signal "VCC")
		(20 "In9.Cu" signal "VCC1")
		(22 "In10.Cu" signal "GND4")
		(24 "In11.Cu" signal "IN4")
		(26 "In12.Cu" signal "GND5")
		(28 "In13.Cu" signal "IN5")
		(30 "In14.Cu" signal "GND6")
		(32 "In15.Cu" signal "IN6")
		(34 "In16.Cu" signal "GND7")
		(2 "B.Cu" signal "BOTTOM")
		(9 "F.Adhes" user "F.Adhesive")
		(11 "B.Adhes" user "B.Adhesive")
		(13 "F.Paste" user "Package Geometry/Pastemask Top")
		(15 "B.Paste" user "Package Geometry/Pastemask Bottom")
		(5 "F.SilkS" user "Ref Des/Silkscreen Top")
		(7 "B.SilkS" user "Ref Des/Silkscreen Bottom")
		(1 "F.Mask" user "Board Geometry/Soldermask Top")
		(3 "B.Mask" user "Board Geometry/Soldermask Bottom")
		(17 "Dwgs.User" user "User.Drawings")
		(19 "Cmts.User" user "User.Comments")
		(21 "Eco1.User" user "User.Eco1")
		(23 "Eco2.User" user "User.Eco2")
		(25 "Edge.Cuts" user "Board Geometry/Outline")
		(27 "Margin" user)
		(31 "F.CrtYd" user "Package Geometry/Place Bound Top")
		(29 "B.CrtYd" user "Package Geometry/Place Bound Bottom")
		(35 "F.Fab" user "Ref Des/Assembly Top")
		(33 "B.Fab" user "Ref Des/Assembly Bottom")
	)
	(footprint ""
		(layer "B.Cu")
		(at 418.570664 -183.327294 180)
		(property "Reference" "PR1777"
			(at 0 0 0)
			(layer "B.SilkS")
			(hide yes)
			(effects
				(font
					(size 1.27 1.27)
				)
				(justify mirror)
			)
		)
		(property "Value" ""
			(at 0 0 0)
			(layer "B.Fab")
			(effects
				(font
					(size 1.27 1.27)
				)
				(justify mirror)
			)
		)
		(duplicate_pad_numbers_are_jumpers no)
		(fp_line
			(start 0.7874 0.4064)
			(end 0.7874 -0.4064)
			(stroke
				(width 0.1524)
				(type default)
			)
			(layer "B.SilkS")
		)
		(fp_line
			(start 0.7874 -0.4064)
			(end -0.7874 -0.4064)
			(stroke
				(width 0.1524)
				(type default)
			)
			(layer "B.SilkS")
		)
		(fp_line
			(start -0.7874 0.4064)
			(end 0.7874 0.4064)
			(stroke
				(width 0.1524)
				(type default)
			)
			(layer "B.SilkS")
		)
		(fp_line
			(start -0.7874 -0.4064)
			(end -0.7874 0.4064)
			(stroke
				(width 0.1524)
				(type default)
			)
			(layer "B.SilkS")
		)
		(fp_line
			(start 0.67945 0.3048)
			(end 0.67945 -0.305054)
			(stroke
				(width 0.1)
				(type default)
			)
			(layer "B.Fab")
		)
		(fp_line
			(start 0.67945 -0.305054)
			(end 0.12065 -0.305054)
			(stroke
				(width 0.1)
				(type default)
			)
			(layer "B.Fab")
		)
		(fp_line
			(start 0.12065 0.3048)
			(end 0.67945 0.3048)
			(stroke
				(width 0.1)
				(type default)
			)
			(layer "B.Fab")
		)
		(fp_line
			(start 0.12065 0.2794)
			(end 0.12065 0.3048)
			(stroke
				(width 0.1)
				(type default)
			)
			(layer "B.Fab")
		)
		(fp_line
			(start 0.12065 -0.2794)
			(end -0.12065 -0.2794)
			(stroke
				(width 0.1)
				(type default)
			)
			(layer "B.Fab")
		)
		(fp_line
			(start 0.12065 -0.305054)
			(end 0.12065 -0.2794)
			(stroke
				(width 0.1)
				(type default)
			)
			(layer "B.Fab")
		)
		(fp_line
			(start -0.120396 0.3048)
			(end -0.120396 0.2794)
			(stroke
				(width 0.1)
				(type default)
			)
			(layer "B.Fab")
		)
		(fp_line
			(start -0.120396 0.2794)
			(end 0.12065 0.2794)
			(stroke
				(width 0.1)
				(type default)
			)
			(layer "B.Fab")
		)
		(fp_line
			(start -0.12065 -0.2794)
			(end -0.12065 -0.3048)
			(stroke
				(width 0.1)
				(type default)
			)
			(layer "B.Fab")
		)
		(fp_line
			(start -0.12065 -0.3048)
			(end -0.67945 -0.3048)
			(stroke
				(width 0.1)
				(type default)
			)
			(layer "B.Fab")
		)
		(fp_line
			(start -0.67945 0.3048)
			(end -0.120396 0.3048)
			(stroke
				(width 0.1)
				(type default)
			)
			(layer "B.Fab")
		)
		(fp_line
			(start -0.67945 -0.3048)
			(end -0.67945 0.3048)
			(stroke
				(width 0.1)
				(type default)
			)
			(layer "B.Fab")
		)
		(pad "1" smd circle
			(at 0.40005 0)
			(size 0 0)
			(layers "B.Cu" "B.Mask" "B.Paste")
			(net "PVCCINFAON_CPU0_VOS2")
		)
		(pad "2" smd circle
			(at -0.40005 0)
			(size 0 0)
			(layers "B.Cu" "B.Mask" "B.Paste")
			(net "PVCCINFAON_CPU0")
		)
	)
	(footprint ""
		(layer "B.Cu")
		(at 446.780158 -177.78476 180)
		(property "Reference" "C1400"
			(at 0 0 0)
			(layer "B.SilkS")
			(hide yes)
			(effects
				(font
					(size 1.27 1.27)
				)
				(justify mirror)
			)
		)
		(property "Value" ""
			(at 0 0 0)
			(layer "B.Fab")
			(effects
				(font
					(size 1.27 1.27)
				)
				(justify mirror)
			)
		)
		(duplicate_pad_numbers_are_jumpers no)
		(fp_line
			(start 1.524 0.762)
			(end 1.524 -0.762)
			(stroke
				(width 0.1524)
				(type default)
			)
			(layer "B.SilkS")
		)
		(fp_line
			(start 1.524 -0.762)
			(end -1.524 -0.762)
			(stroke
				(width 0.1524)
				(type default)
			)
			(layer "B.SilkS")
		)
		(fp_line
			(start -1.524 0.762)
			(end 1.524 0.762)
			(stroke
				(width 0.1524)
				(type default)
			)
			(layer "B.SilkS")
		)
		(fp_line
			(start -1.524 -0.762)
			(end -1.524 0.762)
			(stroke
				(width 0.1524)
				(type default)
			)
			(layer "B.SilkS")
		)
		(fp_line
			(start 1.1049 0.724916)
			(end -1.1049 0.724916)
			(stroke
				(width 0.1)
				(type default)
			)
			(layer "B.Fab")
		)
		(fp_line
			(start 1.1049 -0.724916)
			(end 1.1049 0.724916)
			(stroke
				(width 0.1)
				(type default)
			)
			(layer "B.Fab")
		)
		(fp_line
			(start -1.1049 0.724916)
			(end -1.1049 -0.724916)
			(stroke
				(width 0.1)
				(type default)
			)
			(layer "B.Fab")
		)
		(fp_line
			(start -1.1049 -0.724916)
			(end 1.1049 -0.724916)
			(stroke
				(width 0.1)
				(type default)
			)
			(layer "B.Fab")
		)
		(pad "1" smd rect
			(at 0.889 0 180)
			(size 1.016 1.27)
			(layers "B.Cu" "B.Mask" "B.Paste")
			(net "PVNN_MAIN_CPU0")
		)
		(pad "2" smd rect
			(at -0.889 0 180)
			(size 1.016 1.27)
			(layers "B.Cu" "B.Mask" "B.Paste")
			(net "GND")
		)
	)
	(footprint ""
		(layer "B.Cu")
		(at 416.996626 -173.218602 180)
		(property "Reference" "PR101"
			(at 0 0 0)
			(layer "B.SilkS")
			(hide yes)
			(effects
				(font
					(size 1.27 1.27)
				)
				(justify mirror)
			)
		)
		(property "Value" ""
			(at 0 0 0)
			(layer "B.Fab")
			(effects
				(font
					(size 1.27 1.27)
				)
				(justify mirror)
			)
		)
		(duplicate_pad_numbers_are_jumpers no)
		(fp_line
			(start 0.7874 0.4064)
			(end 0.7874 -0.4064)
			(stroke
				(width 0.1524)
				(type default)
			)
			(layer "B.SilkS")
		)
		(fp_line
			(start 0.7874 -0.4064)
			(end -0.7874 -0.4064)
			(stroke
				(width 0.1524)
				(type default)
			)
			(layer "B.SilkS")
		)
		(fp_line
			(start -0.7874 0.4064)
			(end 0.7874 0.4064)
			(stroke
				(width 0.1524)
				(type default)
			)
			(layer "B.SilkS")
		)
		(fp_line
			(start -0.7874 -0.4064)
			(end -0.7874 0.4064)
			(stroke
				(width 0.1524)
				(type default)
			)
			(layer "B.SilkS")
		)
		(fp_line
			(start 0.67945 0.3048)
			(end 0.67945 -0.305054)
			(stroke
				(width 0.1)
				(type default)
			)
			(layer "B.Fab")
		)
		(fp_line
			(start 0.67945 -0.305054)
			(end 0.12065 -0.305054)
			(stroke
				(width 0.1)
				(type default)
			)
			(layer "B.Fab")
		)
		(fp_line
			(start 0.12065 0.3048)
			(end 0.67945 0.3048)
			(stroke
				(width 0.1)
				(type default)
			)
			(layer "B.Fab")
		)
		(fp_line
			(start 0.12065 0.2794)
			(end 0.12065 0.3048)
			(stroke
				(width 0.1)
				(type default)
			)
			(layer "B.Fab")
		)
		(fp_line
			(start 0.12065 -0.2794)
			(end -0.12065 -0.2794)
			(stroke
				(width 0.1)
				(type default)
			)
			(layer "B.Fab")
		)
		(fp_line
			(start 0.12065 -0.305054)
			(end 0.12065 -0.2794)
			(stroke
				(width 0.1)
				(type default)
			)
			(layer "B.Fab")
		)
		(fp_line
			(start -0.120396 0.3048)
			(end -0.120396 0.2794)
			(stroke
				(width 0.1)
				(type default)
			)
			(layer "B.Fab")
		)
		(fp_line
			(start -0.120396 0.2794)
			(end 0.12065 0.2794)
			(stroke
				(width 0.1)
				(type default)
			)
			(layer "B.Fab")
		)
		(fp_line
			(start -0.12065 -0.2794)
			(end -0.12065 -0.3048)
			(stroke
				(width 0.1)
				(type default)
			)
			(layer "B.Fab")
		)
		(fp_line
			(start -0.12065 -0.3048)
			(end -0.67945 -0.3048)
			(stroke
				(width 0.1)
				(type default)
			)
			(layer "B.Fab")
		)
		(fp_line
			(start -0.67945 0.3048)
			(end -0.120396 0.3048)
			(stroke
				(width 0.1)
				(type default)
			)
			(layer "B.Fab")
		)
		(fp_line
			(start -0.67945 -0.3048)
			(end -0.67945 0.3048)
			(stroke
				(width 0.1)
				(type default)
			)
			(layer "B.Fab")
		)
		(pad "1" smd circle
			(at 0.40005 0)
			(size 0 0)
			(layers "B.Cu" "B.Mask" "B.Paste")
			(net "PVCCFA_EHV_CPU0_PVCC")
		)
		(pad "2" smd circle
			(at -0.40005 0)
			(size 0 0)
			(layers "B.Cu" "B.Mask" "B.Paste")
			(net "PVCCINFAON_CPU0_VDD1")
		)
	)
)
